# S9S_MB_2U (Grand Teton) — schematic netlist excerpt (pin names and nets, part order shuffled) for the footprints in the layout excerpt that follows; sources: Cadence DE-HDL packaged netlist, KiCad conversion of 03242023_DA0F0TMBIJ0_F0T_Motherboard_J_brd_V01_OCP.brd

R4176  Q_RES  10K 1% CHIP  pkg 0402LF  page 257 : A = P3V3_AUX ; B = FM_LPC_ESPI_SEL
R4053  Q_RES  1K 1% CHIP  pkg 0402LF  page 225 : A = PD_GTL2014_BMC_JTAG_DIR_0 ; B = GND

(kicad_pcb
	(version 20260206)
	(generator "pcbnew")
	(generator_version "10.0")
	(general
		(thickness 1.6)
		(legacy_teardrops no)
	)
	(paper "A4")
	(title_block
		(title "03242023_DA0F0TMBIJ0_F0T_Motherboard_J_brd_V01_OCP.brd")
		(comment 1 "Grand Teton / footprints 3535-3536 of 6105")
	)
	(layers
		(0 "F.Cu" signal "TOP")
		(4 "In1.Cu" signal "GND")
		(6 "In2.Cu" signal "IN1")
		(8 "In3.Cu" signal "GND1")
		(10 "In4.Cu" signal "IN2")
		(12 "In5.Cu" signal "GND2")
		(14 "In6.Cu" signal "IN3")
		(16 "In7.Cu" signal "GND3")
		(18 "In8.Cu" signal "VCC")
		(20 "In9.Cu" signal "VCC1")
		(22 "In10.Cu" signal "GND4")
		(24 "In11.Cu" signal "IN4")
		(26 "In12.Cu" signal "GND5")
		(28 "In13.Cu" signal "IN5")
		(30 "In14.Cu" signal "GND6")
		(32 "In15.Cu" signal "IN6")
		(34 "In16.Cu" signal "GND7")
		(2 "B.Cu" signal "BOTTOM")
		(9 "F.Adhes" user "F.Adhesive")
		(11 "B.Adhes" user "B.Adhesive")
		(13 "F.Paste" user "Package Geometry/Pastemask Top")
		(15 "B.Paste" user "Package Geometry/Pastemask Bottom")
		(5 "F.SilkS" user "Ref Des/Silkscreen Top")
		(7 "B.SilkS" user "Ref Des/Silkscreen Bottom")
		(1 "F.Mask" user "Board Geometry/Soldermask Top")
		(3 "B.Mask" user "Board Geometry/Soldermask Bottom")
		(17 "Dwgs.User" user "User.Drawings")
		(19 "Cmts.User" user "User.Comments")
		(21 "Eco1.User" user "User.Eco1")
		(23 "Eco2.User" user "User.Eco2")
		(25 "Edge.Cuts" user "Board Geometry/Outline")
		(27 "Margin" user)
		(31 "F.CrtYd" user "Package Geometry/Place Bound Top")
		(29 "B.CrtYd" user "Package Geometry/Place Bound Bottom")
		(35 "F.Fab" user "Ref Des/Assembly Top")
		(33 "B.Fab" user "Ref Des/Assembly Bottom")
	)
	(footprint ""
		(layer "F.Cu")
		(at 118.49608 -119.846598 90)
		(property "Reference" "R4053"
			(at 0 0 90)
			(layer "F.SilkS")
			(hide yes)
			(effects
				(font
					(size 1.27 1.27)
				)
			)
		)
		(property "Value" ""
			(at 0 0 90)
			(layer "F.Fab")
			(effects
				(font
					(size 1.27 1.27)
				)
			)
		)
		(duplicate_pad_numbers_are_jumpers no)
		(fp_line
			(start 0.7874 -0.4064)
			(end 0.7874 0.4064)
			(stroke
				(width 0.1524)
				(type default)
			)
			(layer "F.SilkS")
		)
		(fp_line
			(start -0.7874 -0.4064)
			(end 0.7874 -0.4064)
			(stroke
				(width 0.1524)
				(type default)
			)
			(layer "F.SilkS")
		)
		(fp_line
			(start 0.7874 0.4064)
			(end -0.7874 0.4064)
			(stroke
				(width 0.1524)
				(type default)
			)
			(layer "F.SilkS")
		)
		(fp_line
			(start -0.7874 0.4064)
			(end -0.7874 -0.4064)
			(stroke
				(width 0.1524)
				(type default)
			)
			(layer "F.SilkS")
		)
		(fp_line
			(start -0.12065 -0.305054)
			(end -0.12065 -0.2794)
			(stroke
				(width 0.1)
				(type default)
			)
			(layer "F.Fab")
		)
		(fp_line
			(start -0.67945 -0.305054)
			(end -0.12065 -0.305054)
			(stroke
				(width 0.1)
				(type default)
			)
			(layer "F.Fab")
		)
		(fp_line
			(start 0.67945 -0.3048)
			(end 0.67945 0.3048)
			(stroke
				(width 0.1)
				(type default)
			)
			(layer "F.Fab")
		)
		(fp_line
			(start 0.12065 -0.3048)
			(end 0.67945 -0.3048)
			(stroke
				(width 0.1)
				(type default)
			)
			(layer "F.Fab")
		)
		(fp_line
			(start 0.12065 -0.2794)
			(end 0.12065 -0.3048)
			(stroke
				(width 0.1)
				(type default)
			)
			(layer "F.Fab")
		)
		(fp_line
			(start -0.12065 -0.2794)
			(end 0.12065 -0.2794)
			(stroke
				(width 0.1)
				(type default)
			)
			(layer "F.Fab")
		)
		(fp_line
			(start 0.120396 0.2794)
			(end -0.12065 0.2794)
			(stroke
				(width 0.1)
				(type default)
			)
			(layer "F.Fab")
		)
		(fp_line
			(start -0.12065 0.2794)
			(end -0.12065 0.3048)
			(stroke
				(width 0.1)
				(type default)
			)
			(layer "F.Fab")
		)
		(fp_line
			(start 0.67945 0.3048)
			(end 0.120396 0.3048)
			(stroke
				(width 0.1)
				(type default)
			)
			(layer "F.Fab")
		)
		(fp_line
			(start 0.120396 0.3048)
			(end 0.120396 0.2794)
			(stroke
				(width 0.1)
				(type default)
			)
			(layer "F.Fab")
		)
		(fp_line
			(start -0.12065 0.3048)
			(end -0.67945 0.3048)
			(stroke
				(width 0.1)
				(type default)
			)
			(layer "F.Fab")
		)
		(fp_line
			(start -0.67945 0.3048)
			(end -0.67945 -0.305054)
			(stroke
				(width 0.1)
				(type default)
			)
			(layer "F.Fab")
		)
		(pad "1" smd circle
			(at -0.40005 0 90)
			(size 0 0)
			(layers "F.Cu" "F.Mask" "F.Paste")
			(net "PD_GTL2014_BMC_JTAG_DIR_0")
		)
		(pad "2" smd circle
			(at 0.40005 0 90)
			(size 0 0)
			(layers "F.Cu" "F.Mask" "F.Paste")
			(net "GND")
		)
	)
	(footprint ""
		(layer "F.Cu")
		(at 169.57294 -28.425648 -90)
		(property "Reference" "R4176"
			(at 0 0 270)
			(layer "F.SilkS")
			(hide yes)
			(effects
				(font
					(size 1.27 1.27)
				)
			)
		)
		(property "Value" ""
			(at 0 0 270)
			(layer "F.Fab")
			(effects
				(font
					(size 1.27 1.27)
				)
			)
		)
		(duplicate_pad_numbers_are_jumpers no)
		(fp_line
			(start -0.7874 0.4064)
			(end -0.7874 -0.4064)
			(stroke
				(width 0.1524)
				(type default)
			)
			(layer "F.SilkS")
		)
		(fp_line
			(start 0.7874 0.4064)
			(end -0.7874 0.4064)
			(stroke
				(width 0.1524)
				(type default)
			)
			(layer "F.SilkS")
		)
		(fp_line
			(start -0.7874 -0.4064)
			(end 0.7874 -0.4064)
			(stroke
				(width 0.1524)
				(type default)
			)
			(layer "F.SilkS")
		)
		(fp_line
			(start 0.7874 -0.4064)
			(end 0.7874 0.4064)
			(stroke
				(width 0.1524)
				(type default)
			)
			(layer "F.SilkS")
		)
		(fp_line
			(start -0.67945 0.3048)
			(end -0.67945 -0.305054)
			(stroke
				(width 0.1)
				(type default)
			)
			(layer "F.Fab")
		)
		(fp_line
			(start -0.12065 0.3048)
			(end -0.67945 0.3048)
			(stroke
				(width 0.1)
				(type default)
			)
			(layer "F.Fab")
		)
		(fp_line
			(start 0.120396 0.3048)
			(end 0.120396 0.2794)
			(stroke
				(width 0.1)
				(type default)
			)
			(layer "F.Fab")
		)
		(fp_line
			(start 0.67945 0.3048)
			(end 0.120396 0.3048)
			(stroke
				(width 0.1)
				(type default)
			)
			(layer "F.Fab")
		)
		(fp_line
			(start -0.12065 0.2794)
			(end -0.12065 0.3048)
			(stroke
				(width 0.1)
				(type default)
			)
			(layer "F.Fab")
		)
		(fp_line
			(start 0.120396 0.2794)
			(end -0.12065 0.2794)
			(stroke
				(width 0.1)
				(type default)
			)
			(layer "F.Fab")
		)
		(fp_line
			(start -0.12065 -0.2794)
			(end 0.12065 -0.2794)
			(stroke
				(width 0.1)
				(type default)
			)
			(layer "F.Fab")
		)
		(fp_line
			(start 0.12065 -0.2794)
			(end 0.12065 -0.3048)
			(stroke
				(width 0.1)
				(type default)
			)
			(layer "F.Fab")
		)
		(fp_line
			(start 0.12065 -0.3048)
			(end 0.67945 -0.3048)
			(stroke
				(width 0.1)
				(type default)
			)
			(layer "F.Fab")
		)
		(fp_line
			(start 0.67945 -0.3048)
			(end 0.67945 0.3048)
			(stroke
				(width 0.1)
				(type default)
			)
			(layer "F.Fab")
		)
		(fp_line
			(start -0.67945 -0.305054)
			(end -0.12065 -0.305054)
			(stroke
				(width 0.1)
				(type default)
			)
			(layer "F.Fab")
		)
		(fp_line
			(start -0.12065 -0.305054)
			(end -0.12065 -0.2794)
			(stroke
				(width 0.1)
				(type default)
			)
			(layer "F.Fab")
		)
		(pad "1" smd circle
			(at -0.40005 0 270)
			(size 0 0)
			(layers "F.Cu" "F.Mask" "F.Paste")
			(net "P3V3_AUX")
		)
		(pad "2" smd circle
			(at 0.40005 0 270)
			(size 0 0)
			(layers "F.Cu" "F.Mask" "F.Paste")
			(net "FM_LPC_ESPI_SEL")
		)
	)
)
